(kicad_pcb
	(version 20260206)
	(generator "pcbnew")
	(generator_version "10.0")
	(general
		(thickness 1.6)
		(legacy_teardrops no)
	)
	(paper "A4")
	(title_block
		(title "Wiwynn_Tioga_Pass_MB.brd")
		(comment 1 "Tioga Pass / footprints 432-436 of 4770")
	)
	(layers
		(0 "F.Cu" signal "TOP")
		(4 "In1.Cu" signal "L2GND")
		(6 "In2.Cu" signal "L3")
		(8 "In3.Cu" signal "L4GND")
		(10 "In4.Cu" signal "L5")
		(12 "In5.Cu" signal "L6GND")
		(14 "In6.Cu" signal "L7VCC")
		(16 "In7.Cu" signal "L8VCC")
		(18 "In8.Cu" signal "L9GND")
		(20 "In9.Cu" signal "L10")
		(22 "In10.Cu" signal "L11GND")
		(24 "In11.Cu" signal "L12")
		(26 "In12.Cu" signal "L13GND")
		(2 "B.Cu" signal "BOTTOM")
		(9 "F.Adhes" user "F.Adhesive")
		(11 "B.Adhes" user "B.Adhesive")
		(13 "F.Paste" user "Package Geometry/Pastemask Top")
		(15 "B.Paste" user "Package Geometry/Pastemask Bottom")
		(5 "F.SilkS" user "Ref Des/Silkscreen Top")
		(7 "B.SilkS" user "Ref Des/Silkscreen Bottom")
		(1 "F.Mask" user "Board Geometry/Soldermask Top")
		(3 "B.Mask" user "Board Geometry/Soldermask Bottom")
		(17 "Dwgs.User" user "User.Drawings")
		(19 "Cmts.User" user "User.Comments")
		(21 "Eco1.User" user "User.Eco1")
		(23 "Eco2.User" user "User.Eco2")
		(25 "Edge.Cuts" user "Board Geometry/Outline")
		(27 "Margin" user)
		(31 "F.CrtYd" user "Package Geometry/Place Bound Top")
		(29 "B.CrtYd" user "Package Geometry/Place Bound Bottom")
		(35 "F.Fab" user "Ref Des/Assembly Top")
		(33 "B.Fab" user "Ref Des/Assembly Bottom")
	)
	(footprint ""
		(layer "F.Cu")
		(at 383.794 -55.4355 180)
		(property "Reference" "R7F28"
			(at 0 0 180)
			(layer "F.SilkS")
			(hide yes)
			(effects
				(font
					(size 1.27 1.27)
				)
			)
		)
		(property "Value" ""
			(at 0 0 180)
			(layer "F.Fab")
			(effects
				(font
					(size 1.27 1.27)
				)
			)
		)
		(duplicate_pad_numbers_are_jumpers no)
		(fp_poly
			(pts
				(xy -0.2794 -0.1016) (xy 0.2794 -0.1016) (xy 0.2794 0.9906) (xy -0.2794 0.9906)
			)
			(stroke
				(width 0)
				(type default)
			)
			(fill no)
			(layer "F.CrtYd")
		)
		(fp_line
			(start 0.2794 0.9906)
			(end 0.2794 -0.1016)
			(stroke
				(width 0.1)
				(type default)
			)
			(layer "F.Fab")
		)
		(fp_line
			(start 0.2794 -0.1016)
			(end -0.2794 -0.1016)
			(stroke
				(width 0.1)
				(type default)
			)
			(layer "F.Fab")
		)
		(fp_line
			(start -0.2794 0.9906)
			(end 0.2794 0.9906)
			(stroke
				(width 0.1)
				(type default)
			)
			(layer "F.Fab")
		)
		(fp_line
			(start -0.2794 -0.1016)
			(end -0.2794 0.9906)
			(stroke
				(width 0.1)
				(type default)
			)
			(layer "F.Fab")
		)
		(pad "1" smd rect
			(at 0 0 180)
			(size 0.508 0.508)
			(layers "F.Cu" "F.Mask" "F.Paste")
			(net "P3V3_STBY")
		)
		(pad "2" smd rect
			(at 0 0.889 180)
			(size 0.508 0.508)
			(layers "F.Cu" "F.Mask" "F.Paste")
			(net "PU_BIOS_SPI_WP0_N")
		)
		(zone
			(layer "F.Cu")
			(hatch none 0.5)
			(connect_pads
				(clearance 0)
			)
			(min_thickness 0.25)
			(keepout
				(tracks not_allowed)
				(vias allowed)
				(pads allowed)
				(copperpour not_allowed)
				(footprints allowed)
			)
			(placement
				(enabled no)
				(sheetname "")
			)
			(fill
				(thermal_gap 0.5)
				(thermal_bridge_width 0.5)
				(island_removal_mode 0)
			)
			(polygon
				(pts
					(xy 384.048 -56.0705) (xy 383.54 -56.0705) (xy 383.54 -55.6895) (xy 384.048 -55.6895)
				)
			)
		)
		(zone
			(layer "F.Cu")
			(hatch none 0.5)
			(connect_pads
				(clearance 0)
			)
			(min_thickness 0.25)
			(keepout
				(tracks allowed)
				(vias not_allowed)
				(pads allowed)
				(copperpour not_allowed)
				(footprints allowed)
			)
			(placement
				(enabled no)
				(sheetname "")
			)
			(fill
				(thermal_gap 0.5)
				(thermal_bridge_width 0.5)
				(island_removal_mode 0)
			)
			(polygon
				(pts
					(xy 384.048 -55.6895) (xy 383.54 -55.6895) (xy 383.54 -56.0705) (xy 384.048 -56.0705)
				)
			)
		)
	)
	(footprint ""
		(layer "F.Cu")
		(at 381.51562 -147.928076 180)
		(property "Reference" "CT68"
			(at -0.8382 -0.67818 180)
			(unlocked yes)
			(layer "F.SilkS")
			(effects
				(font
					(size 0.4064 0.254)
					(thickness 0.1524)
				)
				(justify left)
			)
		)
		(property "Value" ""
			(at 0 0 180)
			(layer "F.Fab")
			(effects
				(font
					(size 1.27 1.27)
				)
			)
		)
		(duplicate_pad_numbers_are_jumpers no)
		(fp_poly
			(pts
				(xy 0.3048 -0.1016) (xy 0.3048 0.9906) (xy -0.3048 0.9906) (xy -0.3048 -0.1016)
			)
			(stroke
				(width 0)
				(type default)
			)
			(fill no)
			(layer "F.CrtYd")
		)
		(fp_line
			(start 0.3048 0.9906)
			(end 0.3048 -0.1016)
			(stroke
				(width 0.1)
				(type default)
			)
			(layer "F.Fab")
		)
		(fp_line
			(start 0.3048 -0.1016)
			(end -0.3048 -0.1016)
			(stroke
				(width 0.1)
				(type default)
			)
			(layer "F.Fab")
		)
		(fp_line
			(start -0.3048 0.9906)
			(end 0.3048 0.9906)
			(stroke
				(width 0.1)
				(type default)
			)
			(layer "F.Fab")
		)
		(fp_line
			(start -0.3048 -0.1016)
			(end -0.3048 0.9906)
			(stroke
				(width 0.1)
				(type default)
			)
			(layer "F.Fab")
		)
		(pad "1" smd rect
			(at 0 0 180)
			(size 0.508 0.508)
			(layers "F.Cu" "F.Mask" "F.Paste")
			(net "VR_P1V05_PCH_STBY_PH1_PHASE_SW")
		)
		(pad "2" smd rect
			(at 0 0.889 180)
			(size 0.508 0.508)
			(layers "F.Cu" "F.Mask" "F.Paste")
			(net "VR_P1V05_PCH_STBY_PH1_SW_RC")
		)
		(zone
			(layer "F.Cu")
			(hatch none 0.5)
			(connect_pads
				(clearance 0)
			)
			(min_thickness 0.25)
			(keepout
				(tracks not_allowed)
				(vias allowed)
				(pads allowed)
				(copperpour not_allowed)
				(footprints allowed)
			)
			(placement
				(enabled no)
				(sheetname "")
			)
			(fill
				(thermal_gap 0.5)
				(thermal_bridge_width 0.5)
				(island_removal_mode 0)
			)
			(polygon
				(pts
					(xy 381.76962 -148.563076) (xy 381.26162 -148.563076) (xy 381.26162 -148.182076) (xy 381.76962 -148.182076)
				)
			)
		)
		(zone
			(layer "F.Cu")
			(hatch none 0.5)
			(connect_pads
				(clearance 0)
			)
			(min_thickness 0.25)
			(keepout
				(tracks allowed)
				(vias not_allowed)
				(pads allowed)
				(copperpour not_allowed)
				(footprints allowed)
			)
			(placement
				(enabled no)
				(sheetname "")
			)
			(fill
				(thermal_gap 0.5)
				(thermal_bridge_width 0.5)
				(island_removal_mode 0)
			)
			(polygon
				(pts
					(xy 381.76962 -148.182076) (xy 381.26162 -148.182076) (xy 381.26162 -148.563076) (xy 381.76962 -148.563076)
				)
			)
		)
	)
	(footprint ""
		(layer "F.Cu")
		(at 323.0245 -117.222016 -90)
		(property "Reference" "C832"
			(at -0.8382 -0.67818 270)
			(unlocked yes)
			(layer "F.SilkS")
			(effects
				(font
					(size 0.4064 0.254)
					(thickness 0.1524)
				)
				(justify left)
			)
		)
		(property "Value" ""
			(at 0 0 270)
			(layer "F.Fab")
			(effects
				(font
					(size 1.27 1.27)
				)
			)
		)
		(duplicate_pad_numbers_are_jumpers no)
		(fp_poly
			(pts
				(xy 0.3048 -0.1016) (xy 0.3048 0.9906) (xy -0.3048 0.9906) (xy -0.3048 -0.1016)
			)
			(stroke
				(width 0)
				(type default)
			)
			(fill no)
			(layer "F.CrtYd")
		)
		(fp_line
			(start -0.3048 0.9906)
			(end 0.3048 0.9906)
			(stroke
				(width 0.1)
				(type default)
			)
			(layer "F.Fab")
		)
		(fp_line
			(start 0.3048 0.9906)
			(end 0.3048 -0.1016)
			(stroke
				(width 0.1)
				(type default)
			)
			(layer "F.Fab")
		)
		(fp_line
			(start -0.3048 -0.1016)
			(end -0.3048 0.9906)
			(stroke
				(width 0.1)
				(type default)
			)
			(layer "F.Fab")
		)
		(fp_line
			(start 0.3048 -0.1016)
			(end -0.3048 -0.1016)
			(stroke
				(width 0.1)
				(type default)
			)
			(layer "F.Fab")
		)
		(pad "1" smd rect
			(at 0 0 270)
			(size 0.508 0.508)
			(layers "F.Cu" "F.Mask" "F.Paste")
			(net "P3E_CPU0_PE1_PCH_TXN<11>")
		)
		(pad "2" smd rect
			(at 0 0.889 270)
			(size 0.508 0.508)
			(layers "F.Cu" "F.Mask" "F.Paste")
			(net "P3E_CPU0_PE1_PCH_CON_TXN<11>")
		)
		(zone
			(layer "F.Cu")
			(hatch none 0.5)
			(connect_pads
				(clearance 0)
			)
			(min_thickness 0.25)
			(keepout
				(tracks not_allowed)
				(vias allowed)
				(pads allowed)
				(copperpour not_allowed)
				(footprints allowed)
			)
			(placement
				(enabled no)
				(sheetname "")
			)
			(fill
				(thermal_gap 0.5)
				(thermal_bridge_width 0.5)
				(island_removal_mode 0)
			)
			(polygon
				(pts
					(xy 322.3895 -117.476016) (xy 322.3895 -116.968016) (xy 322.7705 -116.968016) (xy 322.7705 -117.476016)
				)
			)
		)
		(zone
			(layer "F.Cu")
			(hatch none 0.5)
			(connect_pads
				(clearance 0)
			)
			(min_thickness 0.25)
			(keepout
				(tracks allowed)
				(vias not_allowed)
				(pads allowed)
				(copperpour not_allowed)
				(footprints allowed)
			)
			(placement
				(enabled no)
				(sheetname "")
			)
			(fill
				(thermal_gap 0.5)
				(thermal_bridge_width 0.5)
				(island_removal_mode 0)
			)
			(polygon
				(pts
					(xy 322.7705 -117.476016) (xy 322.7705 -116.968016) (xy 322.3895 -116.968016) (xy 322.3895 -117.476016)
				)
			)
		)
	)
	(footprint ""
		(layer "F.Cu")
		(at 178.054 -84.328 180)
		(property "Reference" "R4D69"
			(at 0 0 180)
			(layer "F.SilkS")
			(hide yes)
			(effects
				(font
					(size 1.27 1.27)
				)
			)
		)
		(property "Value" ""
			(at 0 0 180)
			(layer "F.Fab")
			(effects
				(font
					(size 1.27 1.27)
				)
			)
		)
		(duplicate_pad_numbers_are_jumpers no)
		(fp_poly
			(pts
				(xy -0.2794 -0.1016) (xy 0.2794 -0.1016) (xy 0.2794 0.9906) (xy -0.2794 0.9906)
			)
			(stroke
				(width 0)
				(type default)
			)
			(fill no)
			(layer "F.CrtYd")
		)
		(fp_line
			(start 0.2794 0.9906)
			(end 0.2794 -0.1016)
			(stroke
				(width 0.1)
				(type default)
			)
			(layer "F.Fab")
		)
		(fp_line
			(start 0.2794 -0.1016)
			(end -0.2794 -0.1016)
			(stroke
				(width 0.1)
				(type default)
			)
			(layer "F.Fab")
		)
		(fp_line
			(start -0.2794 0.9906)
			(end 0.2794 0.9906)
			(stroke
				(width 0.1)
				(type default)
			)
			(layer "F.Fab")
		)
		(fp_line
			(start -0.2794 -0.1016)
			(end -0.2794 0.9906)
			(stroke
				(width 0.1)
				(type default)
			)
			(layer "F.Fab")
		)
		(pad "1" smd rect
			(at 0 0 180)
			(size 0.508 0.508)
			(layers "F.Cu" "F.Mask" "F.Paste")
			(net "P3V3")
		)
		(pad "2" smd rect
			(at 0 0.889 180)
			(size 0.508 0.508)
			(layers "F.Cu" "F.Mask" "F.Paste")
			(net "FM_CPU1_MCP_CLK_EN_N")
		)
		(zone
			(layer "F.Cu")
			(hatch none 0.5)
			(connect_pads
				(clearance 0)
			)
			(min_thickness 0.25)
			(keepout
				(tracks not_allowed)
				(vias allowed)
				(pads allowed)
				(copperpour not_allowed)
				(footprints allowed)
			)
			(placement
				(enabled no)
				(sheetname "")
			)
			(fill
				(thermal_gap 0.5)
				(thermal_bridge_width 0.5)
				(island_removal_mode 0)
			)
			(polygon
				(pts
					(xy 178.308 -84.963) (xy 177.8 -84.963) (xy 177.8 -84.582) (xy 178.308 -84.582)
				)
			)
		)
		(zone
			(layer "F.Cu")
			(hatch none 0.5)
			(connect_pads
				(clearance 0)
			)
			(min_thickness 0.25)
			(keepout
				(tracks allowed)
				(vias not_allowed)
				(pads allowed)
				(copperpour not_allowed)
				(footprints allowed)
			)
			(placement
				(enabled no)
				(sheetname "")
			)
			(fill
				(thermal_gap 0.5)
				(thermal_bridge_width 0.5)
				(island_removal_mode 0)
			)
			(polygon
				(pts
					(xy 178.308 -84.582) (xy 177.8 -84.582) (xy 177.8 -84.963) (xy 178.308 -84.963)
				)
			)
		)
	)
	(footprint ""
		(layer "F.Cu")
		(at 12.66952 -3.53441 180)
		(property "Reference" "R12W31"
			(at -0.8382 -0.67818 180)
			(unlocked yes)
			(layer "F.SilkS")
			(effects
				(font
					(size 0.4064 0.254)
					(thickness 0.1524)
				)
				(justify left)
			)
		)
		(property "Value" ""
			(at 0 0 180)
			(layer "F.Fab")
			(effects
				(font
					(size 1.27 1.27)
				)
			)
		)
		(duplicate_pad_numbers_are_jumpers no)
		(fp_poly
			(pts
				(xy -0.2794 -0.1016) (xy 0.2794 -0.1016) (xy 0.2794 0.9906) (xy -0.2794 0.9906)
			)
			(stroke
				(width 0)
				(type default)
			)
			(fill no)
			(layer "F.CrtYd")
		)
		(fp_line
			(start 0.2794 0.9906)
			(end 0.2794 -0.1016)
			(stroke
				(width 0.1)
				(type default)
			)
			(layer "F.Fab")
		)
		(fp_line
			(start 0.2794 -0.1016)
			(end -0.2794 -0.1016)
			(stroke
				(width 0.1)
				(type default)
			)
			(layer "F.Fab")
		)
		(fp_line
			(start -0.2794 0.9906)
			(end 0.2794 0.9906)
			(stroke
				(width 0.1)
				(type default)
			)
			(layer "F.Fab")
		)
		(fp_line
			(start -0.2794 -0.1016)
			(end -0.2794 0.9906)
			(stroke
				(width 0.1)
				(type default)
			)
			(layer "F.Fab")
		)
		(pad "1" smd rect
			(at 0 0 180)
			(size 0.508 0.508)
			(layers "F.Cu" "F.Mask" "F.Paste")
			(net "PU_VR_PVDDQ_GHJ_FAULT1")
		)
		(pad "2" smd rect
			(at 0 0.889 180)
			(size 0.508 0.508)
			(layers "F.Cu" "F.Mask" "F.Paste")
			(net "PWRGD_PVDDQ_GHJ")
		)
		(zone
			(layer "F.Cu")
			(hatch none 0.5)
			(connect_pads
				(clearance 0)
			)
			(min_thickness 0.25)
			(keepout
				(tracks not_allowed)
				(vias allowed)
				(pads allowed)
				(copperpour not_allowed)
				(footprints allowed)
			)
			(placement
				(enabled no)
				(sheetname "")
			)
			(fill
				(thermal_gap 0.5)
				(thermal_bridge_width 0.5)
				(island_removal_mode 0)
			)
			(polygon
				(pts
					(xy 12.92352 -4.16941) (xy 12.41552 -4.16941) (xy 12.41552 -3.78841) (xy 12.92352 -3.78841)
				)
			)
		)
		(zone
			(layer "F.Cu")
			(hatch none 0.5)
			(connect_pads
				(clearance 0)
			)
			(min_thickness 0.25)
			(keepout
				(tracks allowed)
				(vias not_allowed)
				(pads allowed)
				(copperpour not_allowed)
				(footprints allowed)
			)
			(placement
				(enabled no)
				(sheetname "")
			)
			(fill
				(thermal_gap 0.5)
				(thermal_bridge_width 0.5)
				(island_removal_mode 0)
			)
			(polygon
				(pts
					(xy 12.92352 -3.78841) (xy 12.41552 -3.78841) (xy 12.41552 -4.16941) (xy 12.92352 -4.16941)
				)
			)
		)
	)
)
